# S9S_MB_2U (Grand Teton) — schematic netlist excerpt (pin names and nets, part order shuffled) for the footprints in the layout excerpt that follows; sources: Cadence DE-HDL packaged netlist, KiCad conversion of 03242023_DA0F0TMBIJ0_F0T_Motherboard_J_brd_V01_OCP.brd

R2425  Q_RES  33.2 1% CHIP  pkg 0402LF  page 240 : A = SMB_OCP_V3_2_3V3AUX_SCL ; B = SMB_OCP_V3_2_3V3AUX_SCL_R0
C46  Q_CAP  10UF 16V 10% X6S  pkg C0805  page 96 : A = P12V_S3_AUX_CPU0_NVDIMM ; B = GND
R1958  Q_RES  10K 1% CHIP  pkg 0402LF  page 208 : A = P3V3_AUX ; B = PU_CLK_PFT_LOST_N

(kicad_pcb
	(version 20260206)
	(generator "pcbnew")
	(generator_version "10.0")
	(general
		(thickness 1.6)
		(legacy_teardrops no)
	)
	(paper "A4")
	(title_block
		(title "03242023_DA0F0TMBIJ0_F0T_Motherboard_J_brd_V01_OCP.brd")
		(comment 1 "Grand Teton / footprints 5964-5966 of 6105")
	)
	(layers
		(0 "F.Cu" signal "TOP")
		(4 "In1.Cu" signal "GND")
		(6 "In2.Cu" signal "IN1")
		(8 "In3.Cu" signal "GND1")
		(10 "In4.Cu" signal "IN2")
		(12 "In5.Cu" signal "GND2")
		(14 "In6.Cu" signal "IN3")
		(16 "In7.Cu" signal "GND3")
		(18 "In8.Cu" signal "VCC")
		(20 "In9.Cu" signal "VCC1")
		(22 "In10.Cu" signal "GND4")
		(24 "In11.Cu" signal "IN4")
		(26 "In12.Cu" signal "GND5")
		(28 "In13.Cu" signal "IN5")
		(30 "In14.Cu" signal "GND6")
		(32 "In15.Cu" signal "IN6")
		(34 "In16.Cu" signal "GND7")
		(2 "B.Cu" signal "BOTTOM")
		(9 "F.Adhes" user "F.Adhesive")
		(11 "B.Adhes" user "B.Adhesive")
		(13 "F.Paste" user "Package Geometry/Pastemask Top")
		(15 "B.Paste" user "Package Geometry/Pastemask Bottom")
		(5 "F.SilkS" user "Ref Des/Silkscreen Top")
		(7 "B.SilkS" user "Ref Des/Silkscreen Bottom")
		(1 "F.Mask" user "Board Geometry/Soldermask Top")
		(3 "B.Mask" user "Board Geometry/Soldermask Bottom")
		(17 "Dwgs.User" user "User.Drawings")
		(19 "Cmts.User" user "User.Comments")
		(21 "Eco1.User" user "User.Eco1")
		(23 "Eco2.User" user "User.Eco2")
		(25 "Edge.Cuts" user "Board Geometry/Outline")
		(27 "Margin" user)
		(31 "F.CrtYd" user "Package Geometry/Place Bound Top")
		(29 "B.CrtYd" user "Package Geometry/Place Bound Bottom")
		(35 "F.Fab" user "Ref Des/Assembly Top")
		(33 "B.Fab" user "Ref Des/Assembly Bottom")
	)
	(footprint ""
		(layer "B.Cu")
		(at 461.445356 -321.549776 -90)
		(property "Reference" "C46"
			(at 0 0 90)
			(layer "B.SilkS")
			(hide yes)
			(effects
				(font
					(size 1.27 1.27)
				)
				(justify mirror)
			)
		)
		(property "Value" ""
			(at 0 0 90)
			(layer "B.Fab")
			(effects
				(font
					(size 1.27 1.27)
				)
				(justify mirror)
			)
		)
		(duplicate_pad_numbers_are_jumpers no)
		(fp_line
			(start -1.524 0.762)
			(end 1.524 0.762)
			(stroke
				(width 0.1524)
				(type default)
			)
			(layer "B.SilkS")
		)
		(fp_line
			(start 1.524 0.762)
			(end 1.524 -0.762)
			(stroke
				(width 0.1524)
				(type default)
			)
			(layer "B.SilkS")
		)
		(fp_line
			(start -1.524 -0.762)
			(end -1.524 0.762)
			(stroke
				(width 0.1524)
				(type default)
			)
			(layer "B.SilkS")
		)
		(fp_line
			(start 1.524 -0.762)
			(end -1.524 -0.762)
			(stroke
				(width 0.1524)
				(type default)
			)
			(layer "B.SilkS")
		)
		(fp_line
			(start -1.1049 0.724916)
			(end -1.1049 -0.724916)
			(stroke
				(width 0.1)
				(type default)
			)
			(layer "B.Fab")
		)
		(fp_line
			(start 1.1049 0.724916)
			(end -1.1049 0.724916)
			(stroke
				(width 0.1)
				(type default)
			)
			(layer "B.Fab")
		)
		(fp_line
			(start -1.1049 -0.724916)
			(end 1.1049 -0.724916)
			(stroke
				(width 0.1)
				(type default)
			)
			(layer "B.Fab")
		)
		(fp_line
			(start 1.1049 -0.724916)
			(end 1.1049 0.724916)
			(stroke
				(width 0.1)
				(type default)
			)
			(layer "B.Fab")
		)
		(pad "1" smd rect
			(at 0.889 0 270)
			(size 1.016 1.27)
			(layers "B.Cu" "B.Mask" "B.Paste")
			(net "P12V_S3_AUX_CPU0_NVDIMM")
		)
		(pad "2" smd rect
			(at -0.889 0 270)
			(size 1.016 1.27)
			(layers "B.Cu" "B.Mask" "B.Paste")
			(net "GND")
		)
	)
	(footprint ""
		(layer "B.Cu")
		(at 245.8212 -102.112318 180)
		(property "Reference" "R1958"
			(at 0 0 0)
			(layer "B.SilkS")
			(hide yes)
			(effects
				(font
					(size 1.27 1.27)
				)
				(justify mirror)
			)
		)
		(property "Value" ""
			(at 0 0 0)
			(layer "B.Fab")
			(effects
				(font
					(size 1.27 1.27)
				)
				(justify mirror)
			)
		)
		(duplicate_pad_numbers_are_jumpers no)
		(fp_line
			(start 0.7874 0.4064)
			(end 0.7874 -0.4064)
			(stroke
				(width 0.1524)
				(type default)
			)
			(layer "B.SilkS")
		)
		(fp_line
			(start 0.7874 -0.4064)
			(end -0.7874 -0.4064)
			(stroke
				(width 0.1524)
				(type default)
			)
			(layer "B.SilkS")
		)
		(fp_line
			(start -0.7874 0.4064)
			(end 0.7874 0.4064)
			(stroke
				(width 0.1524)
				(type default)
			)
			(layer "B.SilkS")
		)
		(fp_line
			(start -0.7874 -0.4064)
			(end -0.7874 0.4064)
			(stroke
				(width 0.1524)
				(type default)
			)
			(layer "B.SilkS")
		)
		(fp_line
			(start 0.67945 0.3048)
			(end 0.67945 -0.305054)
			(stroke
				(width 0.1)
				(type default)
			)
			(layer "B.Fab")
		)
		(fp_line
			(start 0.67945 -0.305054)
			(end 0.12065 -0.305054)
			(stroke
				(width 0.1)
				(type default)
			)
			(layer "B.Fab")
		)
		(fp_line
			(start 0.12065 0.3048)
			(end 0.67945 0.3048)
			(stroke
				(width 0.1)
				(type default)
			)
			(layer "B.Fab")
		)
		(fp_line
			(start 0.12065 0.2794)
			(end 0.12065 0.3048)
			(stroke
				(width 0.1)
				(type default)
			)
			(layer "B.Fab")
		)
		(fp_line
			(start 0.12065 -0.2794)
			(end -0.12065 -0.2794)
			(stroke
				(width 0.1)
				(type default)
			)
			(layer "B.Fab")
		)
		(fp_line
			(start 0.12065 -0.305054)
			(end 0.12065 -0.2794)
			(stroke
				(width 0.1)
				(type default)
			)
			(layer "B.Fab")
		)
		(fp_line
			(start -0.120396 0.3048)
			(end -0.120396 0.2794)
			(stroke
				(width 0.1)
				(type default)
			)
			(layer "B.Fab")
		)
		(fp_line
			(start -0.120396 0.2794)
			(end 0.12065 0.2794)
			(stroke
				(width 0.1)
				(type default)
			)
			(layer "B.Fab")
		)
		(fp_line
			(start -0.12065 -0.2794)
			(end -0.12065 -0.3048)
			(stroke
				(width 0.1)
				(type default)
			)
			(layer "B.Fab")
		)
		(fp_line
			(start -0.12065 -0.3048)
			(end -0.67945 -0.3048)
			(stroke
				(width 0.1)
				(type default)
			)
			(layer "B.Fab")
		)
		(fp_line
			(start -0.67945 0.3048)
			(end -0.120396 0.3048)
			(stroke
				(width 0.1)
				(type default)
			)
			(layer "B.Fab")
		)
		(fp_line
			(start -0.67945 -0.3048)
			(end -0.67945 0.3048)
			(stroke
				(width 0.1)
				(type default)
			)
			(layer "B.Fab")
		)
		(pad "1" smd circle
			(at 0.40005 0)
			(size 0 0)
			(layers "B.Cu" "B.Mask" "B.Paste")
			(net "P3V3_AUX")
		)
		(pad "2" smd circle
			(at -0.40005 0)
			(size 0 0)
			(layers "B.Cu" "B.Mask" "B.Paste")
			(net "PU_CLK_PFT_LOST_N")
		)
	)
	(footprint ""
		(layer "B.Cu")
		(at 173.22292 -13.762228 90)
		(property "Reference" "R2425"
			(at 0 0 90)
			(layer "B.SilkS")
			(hide yes)
			(effects
				(font
					(size 1.27 1.27)
				)
				(justify mirror)
			)
		)
		(property "Value" ""
			(at 0 0 90)
			(layer "B.Fab")
			(effects
				(font
					(size 1.27 1.27)
				)
				(justify mirror)
			)
		)
		(duplicate_pad_numbers_are_jumpers no)
		(fp_line
			(start 0.7874 -0.4064)
			(end -0.7874 -0.4064)
			(stroke
				(width 0.1524)
				(type default)
			)
			(layer "B.SilkS")
		)
		(fp_line
			(start -0.7874 -0.4064)
			(end -0.7874 0.4064)
			(stroke
				(width 0.1524)
				(type default)
			)
			(layer "B.SilkS")
		)
		(fp_line
			(start 0.7874 0.4064)
			(end 0.7874 -0.4064)
			(stroke
				(width 0.1524)
				(type default)
			)
			(layer "B.SilkS")
		)
		(fp_line
			(start -0.7874 0.4064)
			(end 0.7874 0.4064)
			(stroke
				(width 0.1524)
				(type default)
			)
			(layer "B.SilkS")
		)
		(fp_line
			(start 0.67945 -0.305054)
			(end 0.12065 -0.305054)
			(stroke
				(width 0.1)
				(type default)
			)
			(layer "B.Fab")
		)
		(fp_line
			(start 0.12065 -0.305054)
			(end 0.12065 -0.2794)
			(stroke
				(width 0.1)
				(type default)
			)
			(layer "B.Fab")
		)
		(fp_line
			(start -0.12065 -0.3048)
			(end -0.67945 -0.3048)
			(stroke
				(width 0.1)
				(type default)
			)
			(layer "B.Fab")
		)
		(fp_line
			(start -0.67945 -0.3048)
			(end -0.67945 0.3048)
			(stroke
				(width 0.1)
				(type default)
			)
			(layer "B.Fab")
		)
		(fp_line
			(start 0.12065 -0.2794)
			(end -0.12065 -0.2794)
			(stroke
				(width 0.1)
				(type default)
			)
			(layer "B.Fab")
		)
		(fp_line
			(start -0.12065 -0.2794)
			(end -0.12065 -0.3048)
			(stroke
				(width 0.1)
				(type default)
			)
			(layer "B.Fab")
		)
		(fp_line
			(start 0.12065 0.2794)
			(end 0.12065 0.3048)
			(stroke
				(width 0.1)
				(type default)
			)
			(layer "B.Fab")
		)
		(fp_line
			(start -0.120396 0.2794)
			(end 0.12065 0.2794)
			(stroke
				(width 0.1)
				(type default)
			)
			(layer "B.Fab")
		)
		(fp_line
			(start 0.67945 0.3048)
			(end 0.67945 -0.305054)
			(stroke
				(width 0.1)
				(type default)
			)
			(layer "B.Fab")
		)
		(fp_line
			(start 0.12065 0.3048)
			(end 0.67945 0.3048)
			(stroke
				(width 0.1)
				(type default)
			)
			(layer "B.Fab")
		)
		(fp_line
			(start -0.120396 0.3048)
			(end -0.120396 0.2794)
			(stroke
				(width 0.1)
				(type default)
			)
			(layer "B.Fab")
		)
		(fp_line
			(start -0.67945 0.3048)
			(end -0.120396 0.3048)
			(stroke
				(width 0.1)
				(type default)
			)
			(layer "B.Fab")
		)
		(pad "1" smd circle
			(at 0.40005 0 270)
			(size 0 0)
			(layers "B.Cu" "B.Mask" "B.Paste")
			(net "SMB_OCP_V3_2_3V3AUX_SCL")
		)
		(pad "2" smd circle
			(at -0.40005 0 270)
			(size 0 0)
			(layers "B.Cu" "B.Mask" "B.Paste")
			(net "SMB_OCP_V3_2_3V3AUX_SCL_R0")
		)
	)
)
